(kicad_pcb
	(version 20260206)
	(generator "pcbnew")
	(generator_version "10.0")
	(general
		(thickness 1.6)
		(legacy_teardrops no)
	)
	(paper "A4")
	(title_block
		(title "fcb — Lightning_FCB_BRD.brd")
		(comment 1 "Lightning (Wiwynn / Facebook NVMe JBOF) / footprints 156-160 of 495")
	)
	(layers
		(0 "F.Cu" signal "TOP")
		(4 "In1.Cu" signal "L2GND")
		(6 "In2.Cu" signal "L3VCC")
		(2 "B.Cu" signal "BOTTOM")
		(9 "F.Adhes" user "F.Adhesive")
		(11 "B.Adhes" user "B.Adhesive")
		(13 "F.Paste" user "Package Geometry/Pastemask Top")
		(15 "B.Paste" user "Package Geometry/Pastemask Bottom")
		(5 "F.SilkS" user "Ref Des/Silkscreen Top")
		(7 "B.SilkS" user "Ref Des/Silkscreen Bottom")
		(1 "F.Mask" user "Board Geometry/Soldermask Top")
		(3 "B.Mask" user "Board Geometry/Soldermask Bottom")
		(17 "Dwgs.User" user "User.Drawings")
		(19 "Cmts.User" user "User.Comments")
		(21 "Eco1.User" user "User.Eco1")
		(23 "Eco2.User" user "User.Eco2")
		(25 "Edge.Cuts" user "Board Geometry/Outline")
		(27 "Margin" user)
		(31 "F.CrtYd" user "Package Geometry/Place Bound Top")
		(29 "B.CrtYd" user "Package Geometry/Place Bound Bottom")
		(35 "F.Fab" user "Ref Des/Assembly Top")
		(33 "B.Fab" user "Ref Des/Assembly Bottom")
	)
	(footprint ""
		(layer "F.Cu")
		(at 20.0406 -383.8194)
		(property "Reference" "TC11"
			(at 0 0 0)
			(layer "F.SilkS")
			(hide yes)
			(effects
				(font
					(size 1.27 1.27)
				)
			)
		)
		(property "Value" "ST68U16VDM-1-GP"
			(at 0 -9.6012 0)
			(unlocked yes)
			(layer "F.Fab")
			(hide yes)
			(effects
				(font
					(size 1.016 1.016)
					(thickness 0.1524)
				)
			)
		)
		(property "Device Type" "CT7343H79"
			(at 0 -11.1252 0)
			(unlocked yes)
			(layer "F.Fab")
			(hide yes)
			(effects
				(font
					(size 1.016 1.016)
					(thickness 0.1524)
				)
			)
		)
		(duplicate_pad_numbers_are_jumpers no)
		(fp_line
			(start -2.286 -4.8768)
			(end -2.286 -2.032)
			(stroke
				(width 0.1524)
				(type default)
			)
			(layer "F.SilkS")
		)
		(fp_line
			(start -2.286 4.8768)
			(end -2.286 2.032)
			(stroke
				(width 0.1524)
				(type default)
			)
			(layer "F.SilkS")
		)
		(fp_line
			(start 2.1082 -4.699)
			(end -2.1082 -4.699)
			(stroke
				(width 0.508)
				(type default)
			)
			(layer "F.SilkS")
		)
		(fp_line
			(start 2.286 -4.8768)
			(end -2.286 -4.8768)
			(stroke
				(width 0.1524)
				(type default)
			)
			(layer "F.SilkS")
		)
		(fp_line
			(start 2.286 -2.032)
			(end 2.286 -4.8768)
			(stroke
				(width 0.1524)
				(type default)
			)
			(layer "F.SilkS")
		)
		(fp_line
			(start 2.286 2.032)
			(end 2.286 4.8768)
			(stroke
				(width 0.1524)
				(type default)
			)
			(layer "F.SilkS")
		)
		(fp_line
			(start 2.286 4.8768)
			(end -2.286 4.8768)
			(stroke
				(width 0.1524)
				(type default)
			)
			(layer "F.SilkS")
		)
		(fp_rect
			(start -2.1463 3.6449)
			(end 2.1463 -3.6449)
			(stroke
				(width 0)
				(type default)
			)
			(fill no)
			(layer "F.CrtYd")
		)
		(fp_poly
			(pts
				(xy -2.54 4.953) (xy -2.54 4.2926) (xy -3.81 4.2926) (xy -3.81 -4.2926) (xy -2.54 -4.2926) (xy -2.54 -4.953)
				(xy 2.54 -4.953) (xy 2.54 -4.2926) (xy 3.81 -4.2926) (xy 3.81 -1.6256) (xy 2.1463 -1.6256) (xy 2.1463 -3.6449)
				(xy -2.1463 -3.6449) (xy -2.1463 3.6449) (xy 2.1463 3.6449) (xy 2.1463 -1.6129) (xy 3.81 -1.6129)
				(xy 3.81 4.2926) (xy 2.54 4.2926) (xy 2.54 4.953)
			)
			(stroke
				(width 0)
				(type default)
			)
			(fill no)
			(layer "F.CrtYd")
		)
		(fp_rect
			(start -3.81 4.2926)
			(end -2.54 -4.2926)
			(stroke
				(width 0)
				(type default)
			)
			(fill no)
			(layer "F.Fab")
		)
		(fp_rect
			(start -2.54 4.953)
			(end 2.54 -4.953)
			(stroke
				(width 0)
				(type default)
			)
			(fill no)
			(layer "F.Fab")
		)
		(fp_rect
			(start 2.54 4.2926)
			(end 3.81 -4.2926)
			(stroke
				(width 0)
				(type default)
			)
			(fill no)
			(layer "F.Fab")
		)
		(pad "1" smd rect
			(at 0 -3.1496)
			(size 2.413 2.286)
			(layers "F.Cu" "F.Mask" "F.Paste")
			(net "P12V")
		)
		(pad "2" smd rect
			(at 0 3.1496)
			(size 2.413 2.286)
			(layers "F.Cu" "F.Mask" "F.Paste")
			(net "GND")
		)
		(zone
			(layer "F.Cu")
			(hatch none 0.5)
			(connect_pads
				(clearance 0)
			)
			(min_thickness 0.25)
			(keepout
				(tracks allowed)
				(vias not_allowed)
				(pads allowed)
				(copperpour not_allowed)
				(footprints allowed)
			)
			(placement
				(enabled no)
				(sheetname "")
			)
			(fill
				(thermal_gap 0.5)
				(thermal_bridge_width 0.5)
				(island_removal_mode 0)
			)
			(polygon
				(pts
					(xy 18.5293 -379.222) (xy 21.5519 -379.222) (xy 21.5519 -382.1176) (xy 21.5519 -382.4478) (xy 18.5293 -382.4478)
					(xy 18.5293 -382.1176)
				)
			)
		)
		(zone
			(layer "F.Cu")
			(hatch none 0.5)
			(connect_pads
				(clearance 0)
			)
			(min_thickness 0.25)
			(keepout
				(tracks allowed)
				(vias not_allowed)
				(pads allowed)
				(copperpour not_allowed)
				(footprints allowed)
			)
			(placement
				(enabled no)
				(sheetname "")
			)
			(fill
				(thermal_gap 0.5)
				(thermal_bridge_width 0.5)
				(island_removal_mode 0)
			)
			(polygon
				(pts
					(xy 21.5519 -385.5085) (xy 21.5519 -388.4168) (xy 18.5293 -388.4168) (xy 18.5293 -385.5212) (xy 18.5293 -385.191)
					(xy 21.5519 -385.191)
				)
			)
		)
	)
	(footprint ""
		(layer "F.Cu")
		(at 36.659566 -152.08631 90)
		(property "Reference" "TP14"
			(at 0 0 90)
			(layer "F.SilkS")
			(hide yes)
			(effects
				(font
					(size 1.27 1.27)
				)
			)
		)
		(property "Value" "TPAD32-GP"
			(at 0 -3.166364 90)
			(unlocked yes)
			(layer "F.Fab")
			(hide yes)
			(effects
				(font
					(size 1.016 1.016)
					(thickness 0.1524)
				)
			)
		)
		(property "Device Type" "TPAD32"
			(at 0 -4.690618 90)
			(unlocked yes)
			(layer "F.Fab")
			(hide yes)
			(effects
				(font
					(size 1.016 1.016)
					(thickness 0.1524)
				)
			)
		)
		(duplicate_pad_numbers_are_jumpers no)
		(fp_poly
			(pts
				(arc
					(start 0.7112 0)
					(mid -0.7112 0)
					(end 0.7112 0)
				)
			)
			(stroke
				(width 0)
				(type default)
			)
			(fill no)
			(layer "F.CrtYd")
		)
		(fp_poly
			(pts
				(arc
					(start 0.7112 0)
					(mid -0.7112 0)
					(end 0.7112 0)
				)
			)
			(stroke
				(width 0)
				(type default)
			)
			(fill no)
			(layer "F.Fab")
		)
		(pad "1" smd circle
			(at 0 0 90)
			(size 0.8128 0.8128)
			(layers "F.Cu" "F.Mask" "F.Paste")
			(net "NCT7904_VSEN14")
		)
	)
	(footprint ""
		(layer "F.Cu")
		(at 17.018 -185.42 -90)
		(property "Reference" "R79"
			(at 0 0 270)
			(layer "F.SilkS")
			(hide yes)
			(effects
				(font
					(size 1.27 1.27)
				)
			)
		)
		(property "Value" "4K7R2F-GP"
			(at 0.064008 -3.993896 270)
			(unlocked yes)
			(layer "F.Fab")
			(hide yes)
			(effects
				(font
					(size 1.016 1.016)
					(thickness 0.1524)
				)
			)
		)
		(property "Device Type" "R402H16"
			(at 0.064008 -5.517896 270)
			(unlocked yes)
			(layer "F.Fab")
			(hide yes)
			(effects
				(font
					(size 1.016 1.016)
					(thickness 0.1524)
				)
			)
		)
		(duplicate_pad_numbers_are_jumpers no)
		(fp_line
			(start -0.508 -0.9398)
			(end -0.508 0.9398)
			(stroke
				(width 0.1524)
				(type default)
			)
			(layer "F.SilkS")
		)
		(fp_line
			(start 0.508 -0.9398)
			(end -0.508 -0.9398)
			(stroke
				(width 0.1524)
				(type default)
			)
			(layer "F.SilkS")
		)
		(fp_rect
			(start -0.508 0.9398)
			(end 0.508 -0.9398)
			(stroke
				(width 0)
				(type default)
			)
			(fill no)
			(layer "F.CrtYd")
		)
		(fp_rect
			(start -0.508 0.9398)
			(end 0.508 -0.9398)
			(stroke
				(width 0)
				(type default)
			)
			(fill no)
			(layer "F.Fab")
		)
		(pad "1" smd custom
			(at 0 -0.4445 270)
			(size 0.1397 0.1397)
			(layers "F.Cu" "F.Mask" "F.Paste")
			(net "P12V")
			(options
				(clearance outline)
				(anchor circle)
			)
			(primitives
				(gr_poly
					(pts
						(arc
							(start -0.1778 -0.2794)
							(mid -0.249642 -0.249642)
							(end -0.2794 -0.1778)
						)
						(arc
							(start -0.2794 0.1778)
							(mid -0.249642 0.249642)
							(end -0.1778 0.2794)
						)
						(arc
							(start 0.1778 0.2794)
							(mid 0.249642 0.249642)
							(end 0.2794 0.1778)
						)
						(arc
							(start 0.2794 -0.1778)
							(mid 0.249642 -0.249642)
							(end 0.1778 -0.2794)
						)
					)
					(width 0)
					(fill yes)
				)
			)
		)
		(pad "2" smd custom
			(at 0 0.4445 270)
			(size 0.1397 0.1397)
			(layers "F.Cu" "F.Mask" "F.Paste")
			(net "PWM_OUT_FAN4_NET")
			(options
				(clearance outline)
				(anchor circle)
			)
			(primitives
				(gr_poly
					(pts
						(arc
							(start -0.1778 -0.2794)
							(mid -0.249642 -0.249642)
							(end -0.2794 -0.1778)
						)
						(arc
							(start -0.2794 0.1778)
							(mid -0.249642 0.249642)
							(end -0.1778 0.2794)
						)
						(arc
							(start 0.1778 0.2794)
							(mid 0.249642 0.249642)
							(end 0.2794 0.1778)
						)
						(arc
							(start 0.2794 -0.1778)
							(mid 0.249642 -0.249642)
							(end 0.1778 -0.2794)
						)
					)
					(width 0)
					(fill yes)
				)
			)
		)
	)
	(footprint ""
		(layer "F.Cu")
		(at 43.9166 -106.2736 90)
		(property "Reference" "TC7"
			(at 0 0 90)
			(layer "F.SilkS")
			(hide yes)
			(effects
				(font
					(size 1.27 1.27)
				)
			)
		)
		(property "Value" "ST68U16VDM-1-GP"
			(at 0 -9.6012 90)
			(unlocked yes)
			(layer "F.Fab")
			(hide yes)
			(effects
				(font
					(size 1.016 1.016)
					(thickness 0.1524)
				)
			)
		)
		(property "Device Type" "CT7343H79"
			(at 0 -11.1252 90)
			(unlocked yes)
			(layer "F.Fab")
			(hide yes)
			(effects
				(font
					(size 1.016 1.016)
					(thickness 0.1524)
				)
			)
		)
		(duplicate_pad_numbers_are_jumpers no)
		(fp_line
			(start 2.286 -4.8768)
			(end -2.286 -4.8768)
			(stroke
				(width 0.1524)
				(type default)
			)
			(layer "F.SilkS")
		)
		(fp_line
			(start -2.286 -4.8768)
			(end -2.286 -2.032)
			(stroke
				(width 0.1524)
				(type default)
			)
			(layer "F.SilkS")
		)
		(fp_line
			(start 2.1082 -4.699)
			(end -2.1082 -4.699)
			(stroke
				(width 0.508)
				(type default)
			)
			(layer "F.SilkS")
		)
		(fp_line
			(start 2.286 -2.032)
			(end 2.286 -4.8768)
			(stroke
				(width 0.1524)
				(type default)
			)
			(layer "F.SilkS")
		)
		(fp_line
			(start 2.286 2.032)
			(end 2.286 4.8768)
			(stroke
				(width 0.1524)
				(type default)
			)
			(layer "F.SilkS")
		)
		(fp_line
			(start 2.286 4.8768)
			(end -2.286 4.8768)
			(stroke
				(width 0.1524)
				(type default)
			)
			(layer "F.SilkS")
		)
		(fp_line
			(start -2.286 4.8768)
			(end -2.286 2.032)
			(stroke
				(width 0.1524)
				(type default)
			)
			(layer "F.SilkS")
		)
		(fp_rect
			(start -2.1463 3.6449)
			(end 2.1463 -3.6449)
			(stroke
				(width 0)
				(type default)
			)
			(fill no)
			(layer "F.CrtYd")
		)
		(fp_poly
			(pts
				(xy -2.54 4.953) (xy -2.54 4.2926) (xy -3.81 4.2926) (xy -3.81 -4.2926) (xy -2.54 -4.2926) (xy -2.54 -4.953)
				(xy 2.54 -4.953) (xy 2.54 -4.2926) (xy 3.81 -4.2926) (xy 3.81 -1.6256) (xy 2.1463 -1.6256) (xy 2.1463 -3.6449)
				(xy -2.1463 -3.6449) (xy -2.1463 3.6449) (xy 2.1463 3.6449) (xy 2.1463 -1.6129) (xy 3.81 -1.6129)
				(xy 3.81 4.2926) (xy 2.54 4.2926) (xy 2.54 4.953)
			)
			(stroke
				(width 0)
				(type default)
			)
			(fill no)
			(layer "F.CrtYd")
		)
		(fp_rect
			(start 2.54 4.2926)
			(end 3.81 -4.2926)
			(stroke
				(width 0)
				(type default)
			)
			(fill no)
			(layer "F.Fab")
		)
		(fp_rect
			(start -3.81 4.2926)
			(end -2.54 -4.2926)
			(stroke
				(width 0)
				(type default)
			)
			(fill no)
			(layer "F.Fab")
		)
		(fp_rect
			(start -2.54 4.953)
			(end 2.54 -4.953)
			(stroke
				(width 0)
				(type default)
			)
			(fill no)
			(layer "F.Fab")
		)
		(pad "1" smd rect
			(at 0 -3.1496 90)
			(size 2.413 2.286)
			(layers "F.Cu" "F.Mask" "F.Paste")
			(net "P12VL")
		)
		(pad "2" smd rect
			(at 0 3.1496 90)
			(size 2.413 2.286)
			(layers "F.Cu" "F.Mask" "F.Paste")
			(net "GND")
		)
		(zone
			(layer "F.Cu")
			(hatch none 0.5)
			(connect_pads
				(clearance 0)
			)
			(min_thickness 0.25)
			(keepout
				(tracks allowed)
				(vias not_allowed)
				(pads allowed)
				(copperpour not_allowed)
				(footprints allowed)
			)
			(placement
				(enabled no)
				(sheetname "")
			)
			(fill
				(thermal_gap 0.5)
				(thermal_bridge_width 0.5)
				(island_removal_mode 0)
			)
			(polygon
				(pts
					(xy 42.2275 -107.7849) (xy 39.3192 -107.7849) (xy 39.3192 -104.7623) (xy 42.2148 -104.7623) (xy 42.545 -104.7623)
					(xy 42.545 -107.7849)
				)
			)
		)
		(zone
			(layer "F.Cu")
			(hatch none 0.5)
			(connect_pads
				(clearance 0)
			)
			(min_thickness 0.25)
			(keepout
				(tracks allowed)
				(vias not_allowed)
				(pads allowed)
				(copperpour not_allowed)
				(footprints allowed)
			)
			(placement
				(enabled no)
				(sheetname "")
			)
			(fill
				(thermal_gap 0.5)
				(thermal_bridge_width 0.5)
				(island_removal_mode 0)
			)
			(polygon
				(pts
					(xy 48.514 -104.7623) (xy 48.514 -107.7849) (xy 45.6184 -107.7849) (xy 45.2882 -107.7849) (xy 45.2882 -104.7623)
					(xy 45.6184 -104.7623)
				)
			)
		)
	)
	(footprint ""
		(layer "F.Cu")
		(at 29.1592 -253.8984 180)
		(property "Reference" "R45"
			(at 0 0 180)
			(layer "F.SilkS")
			(hide yes)
			(effects
				(font
					(size 1.27 1.27)
				)
			)
		)
		(property "Value" "0R2J-2-GP"
			(at 0.064008 -3.993896 180)
			(unlocked yes)
			(layer "F.Fab")
			(hide yes)
			(effects
				(font
					(size 1.016 1.016)
					(thickness 0.1524)
				)
			)
		)
		(property "Device Type" "R402H16"
			(at 0.064008 -5.517896 180)
			(unlocked yes)
			(layer "F.Fab")
			(hide yes)
			(effects
				(font
					(size 1.016 1.016)
					(thickness 0.1524)
				)
			)
		)
		(duplicate_pad_numbers_are_jumpers no)
		(fp_line
			(start 0.508 -0.9398)
			(end -0.508 -0.9398)
			(stroke
				(width 0.1524)
				(type default)
			)
			(layer "F.SilkS")
		)
		(fp_line
			(start -0.508 -0.9398)
			(end -0.508 0.9398)
			(stroke
				(width 0.1524)
				(type default)
			)
			(layer "F.SilkS")
		)
		(fp_rect
			(start -0.508 0.9398)
			(end 0.508 -0.9398)
			(stroke
				(width 0)
				(type default)
			)
			(fill no)
			(layer "F.CrtYd")
		)
		(fp_rect
			(start -0.508 0.9398)
			(end 0.508 -0.9398)
			(stroke
				(width 0)
				(type default)
			)
			(fill no)
			(layer "F.Fab")
		)
		(pad "1" smd custom
			(at 0 -0.4445 180)
			(size 0.1397 0.1397)
			(layers "F.Cu" "F.Mask" "F.Paste")
			(net "EEPROM_WP")
			(options
				(clearance outline)
				(anchor circle)
			)
			(primitives
				(gr_poly
					(pts
						(arc
							(start -0.1778 -0.2794)
							(mid -0.249642 -0.249642)
							(end -0.2794 -0.1778)
						)
						(arc
							(start -0.2794 0.1778)
							(mid -0.249642 0.249642)
							(end -0.1778 0.2794)
						)
						(arc
							(start 0.1778 0.2794)
							(mid 0.249642 0.249642)
							(end 0.2794 0.1778)
						)
						(arc
							(start 0.2794 -0.1778)
							(mid 0.249642 -0.249642)
							(end 0.1778 -0.2794)
						)
					)
					(width 0)
					(fill yes)
				)
			)
		)
		(pad "2" smd custom
			(at 0 0.4445 180)
			(size 0.1397 0.1397)
			(layers "F.Cu" "F.Mask" "F.Paste")
			(net "GND")
			(options
				(clearance outline)
				(anchor circle)
			)
			(primitives
				(gr_poly
					(pts
						(arc
							(start -0.1778 -0.2794)
							(mid -0.249642 -0.249642)
							(end -0.2794 -0.1778)
						)
						(arc
							(start -0.2794 0.1778)
							(mid -0.249642 0.249642)
							(end -0.1778 0.2794)
						)
						(arc
							(start 0.1778 0.2794)
							(mid 0.249642 0.249642)
							(end 0.2794 0.1778)
						)
						(arc
							(start 0.2794 -0.1778)
							(mid 0.249642 -0.249642)
							(end 0.1778 -0.2794)
						)
					)
					(width 0)
					(fill yes)
				)
			)
		)
	)
)
